# BASEBOARD_FAB2 (Tioga Pass) — schematic netlist excerpt (pin names and nets, part order shuffled) for the footprints in the layout excerpt that follows; sources: Cadence DE-HDL packaged netlist, KiCad conversion of Wiwynn_Tioga_Pass_MB.brd

R2R4  RES  0.0 5% CHIP  pkg 0402  page 191 : A = FM_ADR_SMI_GPIO_R_N ; B = FM_ADR_SMI_GPIO_N
R1M14  RES  200.0 1% CHIP  pkg 0402  page 186 : A = RST_PCIE_CPU_DEV0_N ; B = RST_PCIE_CPU_DEV0_R_N
C6P8  CAPP  470UF 2.5V 20% ALUM  pkg 3018  page 203 : A = PVCCIN_CPU0 ; B = GND

(kicad_pcb
	(version 20260206)
	(generator "pcbnew")
	(generator_version "10.0")
	(general
		(thickness 1.6)
		(legacy_teardrops no)
	)
	(paper "A4")
	(title_block
		(title "Wiwynn_Tioga_Pass_MB.brd")
		(comment 1 "Tioga Pass / footprints 3147-3149 of 4770")
	)
	(layers
		(0 "F.Cu" signal "TOP")
		(4 "In1.Cu" signal "L2GND")
		(6 "In2.Cu" signal "L3")
		(8 "In3.Cu" signal "L4GND")
		(10 "In4.Cu" signal "L5")
		(12 "In5.Cu" signal "L6GND")
		(14 "In6.Cu" signal "L7VCC")
		(16 "In7.Cu" signal "L8VCC")
		(18 "In8.Cu" signal "L9GND")
		(20 "In9.Cu" signal "L10")
		(22 "In10.Cu" signal "L11GND")
		(24 "In11.Cu" signal "L12")
		(26 "In12.Cu" signal "L13GND")
		(2 "B.Cu" signal "BOTTOM")
		(9 "F.Adhes" user "F.Adhesive")
		(11 "B.Adhes" user "B.Adhesive")
		(13 "F.Paste" user "Package Geometry/Pastemask Top")
		(15 "B.Paste" user "Package Geometry/Pastemask Bottom")
		(5 "F.SilkS" user "Ref Des/Silkscreen Top")
		(7 "B.SilkS" user "Ref Des/Silkscreen Bottom")
		(1 "F.Mask" user "Board Geometry/Soldermask Top")
		(3 "B.Mask" user "Board Geometry/Soldermask Bottom")
		(17 "Dwgs.User" user "User.Drawings")
		(19 "Cmts.User" user "User.Comments")
		(21 "Eco1.User" user "User.Eco1")
		(23 "Eco2.User" user "User.Eco2")
		(25 "Edge.Cuts" user "Board Geometry/Outline")
		(27 "Margin" user)
		(31 "F.CrtYd" user "Package Geometry/Place Bound Top")
		(29 "B.CrtYd" user "Package Geometry/Place Bound Bottom")
		(35 "F.Fab" user "Ref Des/Assembly Top")
		(33 "B.Fab" user "Ref Des/Assembly Bottom")
	)
	(footprint ""
		(layer "B.Cu")
		(at 474.345 -120.8278)
		(property "Reference" "R1M14"
			(at 0 0 0)
			(layer "B.SilkS")
			(hide yes)
			(effects
				(font
					(size 1.27 1.27)
				)
				(justify mirror)
			)
		)
		(property "Value" ""
			(at 0 0 0)
			(layer "B.Fab")
			(effects
				(font
					(size 1.27 1.27)
				)
				(justify mirror)
			)
		)
		(duplicate_pad_numbers_are_jumpers no)
		(fp_rect
			(start -0.2794 0.9906)
			(end 0.2794 -0.1016)
			(stroke
				(width 0)
				(type default)
			)
			(fill no)
			(layer "B.CrtYd")
		)
		(fp_line
			(start -0.2794 -0.1016)
			(end 0.2794 -0.1016)
			(stroke
				(width 0.1)
				(type default)
			)
			(layer "B.Fab")
		)
		(fp_line
			(start -0.2794 0.9906)
			(end -0.2794 -0.1016)
			(stroke
				(width 0.1)
				(type default)
			)
			(layer "B.Fab")
		)
		(fp_line
			(start 0.2794 -0.1016)
			(end 0.2794 0.9906)
			(stroke
				(width 0.1)
				(type default)
			)
			(layer "B.Fab")
		)
		(fp_line
			(start 0.2794 0.9906)
			(end -0.2794 0.9906)
			(stroke
				(width 0.1)
				(type default)
			)
			(layer "B.Fab")
		)
		(pad "1" smd rect
			(at 0 0 180)
			(size 0.508 0.508)
			(layers "B.Cu" "B.Mask" "B.Paste")
			(net "RST_PCIE_CPU_DEV0_N")
		)
		(pad "2" smd rect
			(at 0 0.889 180)
			(size 0.508 0.508)
			(layers "B.Cu" "B.Mask" "B.Paste")
			(net "RST_PCIE_CPU_DEV0_R_N")
		)
		(zone
			(layer "B.Cu")
			(hatch none 0.5)
			(connect_pads
				(clearance 0)
			)
			(min_thickness 0.25)
			(keepout
				(tracks not_allowed)
				(vias allowed)
				(pads allowed)
				(copperpour not_allowed)
				(footprints allowed)
			)
			(placement
				(enabled no)
				(sheetname "")
			)
			(fill
				(thermal_gap 0.5)
				(thermal_bridge_width 0.5)
				(island_removal_mode 0)
			)
			(polygon
				(pts
					(xy 474.091 -120.1928) (xy 474.599 -120.1928) (xy 474.599 -120.5738) (xy 474.091 -120.5738)
				)
			)
		)
		(zone
			(layer "B.Cu")
			(hatch none 0.5)
			(connect_pads
				(clearance 0)
			)
			(min_thickness 0.25)
			(keepout
				(tracks allowed)
				(vias not_allowed)
				(pads allowed)
				(copperpour not_allowed)
				(footprints allowed)
			)
			(placement
				(enabled no)
				(sheetname "")
			)
			(fill
				(thermal_gap 0.5)
				(thermal_bridge_width 0.5)
				(island_removal_mode 0)
			)
			(polygon
				(pts
					(xy 474.091 -120.1928) (xy 474.599 -120.1928) (xy 474.599 -120.5738) (xy 474.091 -120.5738)
				)
			)
		)
	)
	(footprint ""
		(layer "B.Cu")
		(at 210.847432 -83.947 -90)
		(property "Reference" "C6P8"
			(at 0.66167 -3.782568 0)
			(unlocked yes)
			(layer "B.SilkS")
			(effects
				(font
					(size 0.7874 0.5842)
					(thickness 0.1524)
				)
				(justify mirror)
			)
		)
		(property "Value" ""
			(at 0 0 90)
			(layer "B.Fab")
			(effects
				(font
					(size 1.27 1.27)
				)
				(justify mirror)
			)
		)
		(duplicate_pad_numbers_are_jumpers no)
		(fp_line
			(start -2.286 7.366)
			(end -1.600708 7.366)
			(stroke
				(width 0.1524)
				(type default)
			)
			(layer "B.SilkS")
		)
		(fp_line
			(start -2.286 7.366)
			(end -2.286 1.63195)
			(stroke
				(width 0.1524)
				(type default)
			)
			(layer "B.SilkS")
		)
		(fp_line
			(start 2.286 7.366)
			(end 1.60147 7.366)
			(stroke
				(width 0.1524)
				(type default)
			)
			(layer "B.SilkS")
		)
		(fp_line
			(start 2.286 7.366)
			(end 2.286 1.632712)
			(stroke
				(width 0.1524)
				(type default)
			)
			(layer "B.SilkS")
		)
		(fp_line
			(start -2.504948 1.633728)
			(end -1.6002 1.633728)
			(stroke
				(width 0.1524)
				(type default)
			)
			(layer "B.SilkS")
		)
		(fp_line
			(start 2.563114 1.633728)
			(end 1.6002 1.633728)
			(stroke
				(width 0.1524)
				(type default)
			)
			(layer "B.SilkS")
		)
		(fp_line
			(start -2.504948 -1.616456)
			(end -2.504948 1.633728)
			(stroke
				(width 0.1524)
				(type default)
			)
			(layer "B.SilkS")
		)
		(fp_line
			(start -1.6002 -1.616456)
			(end -2.504948 -1.616456)
			(stroke
				(width 0.1524)
				(type default)
			)
			(layer "B.SilkS")
		)
		(fp_line
			(start 1.6002 -1.616456)
			(end 2.563114 -1.616456)
			(stroke
				(width 0.1524)
				(type default)
			)
			(layer "B.SilkS")
		)
		(fp_line
			(start 2.563114 -1.616456)
			(end 2.563114 1.633728)
			(stroke
				(width 0.1524)
				(type default)
			)
			(layer "B.SilkS")
		)
		(fp_rect
			(start 2.286 7.366)
			(end -2.286 -0.254)
			(stroke
				(width 0)
				(type default)
			)
			(fill no)
			(layer "B.CrtYd")
		)
		(fp_line
			(start -2.286 7.366)
			(end 2.286 7.366)
			(stroke
				(width 0.1)
				(type default)
			)
			(layer "B.Fab")
		)
		(fp_line
			(start 2.286 7.366)
			(end 2.286 -0.254)
			(stroke
				(width 0.1)
				(type default)
			)
			(layer "B.Fab")
		)
		(fp_line
			(start -2.286 -0.254)
			(end -2.286 7.366)
			(stroke
				(width 0.1)
				(type default)
			)
			(layer "B.Fab")
		)
		(fp_line
			(start 2.286 -0.254)
			(end -2.286 -0.254)
			(stroke
				(width 0.1)
				(type default)
			)
			(layer "B.Fab")
		)
		(pad "1" smd rect
			(at 0 0 90)
			(size 2.54 3.048)
			(layers "B.Cu" "B.Mask" "B.Paste")
			(net "PVCCIN_CPU0")
		)
		(pad "2" smd rect
			(at 0 7.112 90)
			(size 2.54 3.048)
			(layers "B.Cu" "B.Mask" "B.Paste")
			(net "GND")
		)
	)
	(footprint ""
		(layer "B.Cu")
		(at 376.174 -66.929)
		(property "Reference" "R2R4"
			(at 0 0 0)
			(layer "B.SilkS")
			(hide yes)
			(effects
				(font
					(size 1.27 1.27)
				)
				(justify mirror)
			)
		)
		(property "Value" ""
			(at 0 0 0)
			(layer "B.Fab")
			(effects
				(font
					(size 1.27 1.27)
				)
				(justify mirror)
			)
		)
		(duplicate_pad_numbers_are_jumpers no)
		(fp_poly
			(pts
				(xy 0.2794 -0.1016) (xy -0.2794 -0.1016) (xy -0.2794 0.9906) (xy 0.2794 0.9906)
			)
			(stroke
				(width 0)
				(type default)
			)
			(fill no)
			(layer "B.CrtYd")
		)
		(fp_line
			(start -0.2794 -0.1016)
			(end 0.2794 -0.1016)
			(stroke
				(width 0.1)
				(type default)
			)
			(layer "B.Fab")
		)
		(fp_line
			(start -0.2794 0.9906)
			(end -0.2794 -0.1016)
			(stroke
				(width 0.1)
				(type default)
			)
			(layer "B.Fab")
		)
		(fp_line
			(start 0.2794 -0.1016)
			(end 0.2794 0.9906)
			(stroke
				(width 0.1)
				(type default)
			)
			(layer "B.Fab")
		)
		(fp_line
			(start 0.2794 0.9906)
			(end -0.2794 0.9906)
			(stroke
				(width 0.1)
				(type default)
			)
			(layer "B.Fab")
		)
		(pad "1" smd rect
			(at 0 0 180)
			(size 0.508 0.508)
			(layers "B.Cu" "B.Mask" "B.Paste")
			(net "FM_ADR_SMI_GPIO_R_N")
		)
		(pad "2" smd rect
			(at 0 0.889 180)
			(size 0.508 0.508)
			(layers "B.Cu" "B.Mask" "B.Paste")
			(net "FM_ADR_SMI_GPIO_N")
		)
		(zone
			(layer "B.Cu")
			(hatch none 0.5)
			(connect_pads
				(clearance 0)
			)
			(min_thickness 0.25)
			(keepout
				(tracks allowed)
				(vias not_allowed)
				(pads allowed)
				(copperpour not_allowed)
				(footprints allowed)
			)
			(placement
				(enabled no)
				(sheetname "")
			)
			(fill
				(thermal_gap 0.5)
				(thermal_bridge_width 0.5)
				(island_removal_mode 0)
			)
			(polygon
				(pts
					(xy 376.428 -66.675) (xy 375.92 -66.675) (xy 375.92 -66.294) (xy 376.428 -66.294)
				)
			)
		)
		(zone
			(layer "B.Cu")
			(hatch none 0.5)
			(connect_pads
				(clearance 0)
			)
			(min_thickness 0.25)
			(keepout
				(tracks not_allowed)
				(vias allowed)
				(pads allowed)
				(copperpour not_allowed)
				(footprints allowed)
			)
			(placement
				(enabled no)
				(sheetname "")
			)
			(fill
				(thermal_gap 0.5)
				(thermal_bridge_width 0.5)
				(island_removal_mode 0)
			)
			(polygon
				(pts
					(xy 376.428 -66.294) (xy 375.92 -66.294) (xy 375.92 -66.675) (xy 376.428 -66.675)
				)
			)
		)
	)
)
